# T6G (Grand Teton) — schematic netlist excerpt (pin names and nets, part order shuffled) for the footprints in the layout excerpt that follows; sources: Cadence DE-HDL packaged netlist, KiCad conversion of 04192023_DAF0TMB3IC0_F0TG_MB_C_brd_V02_OCP.brd

J41  SCONN168_ME1016810202011  IO  pkg CON_F168S2H7D_P0-6W2-95_LUH  page 150
  GND_A1  = SMB_OCP_SFF_3V3AUX_SCL_R0
  GND_A2  = SMB_OCP_SFF_3V3AUX_SDA_R0
  GND_A3  = SMB_CPU0_CPU1_APML_SCL_R
  GND_A4  = SMB_CPU0_CPU1_APML_SDA_R
  GND_A5  = SMB_VR_3V3AUX_SCL_R0
  GND_A6  = SMB_VR_3V3AUX_SDA_R0
  SMCLK  = SMB_CPU0_CPU1_SEC_SCL_R
  SMDAT  = SMB_CPU0_CPU1_SEC_SDA_R
  \smrst#\  = I3C_BMC_SWB_SCL
  \prsnta#\  = I3C_BMC_SWB_SDA
  \perst1#\  = SMB_OCP_V3_2_3V3AUX_SCL_R0
  \prsntb2#\  = SMB_OCP_V3_2_3V3AUX_SDA_R0
  GND_A13  = GND
  REFCLKN1  = CLK_100M_CPU0_CLK01_DP
  REFCLKP1  = CLK_100M_CPU0_CLK01_DN
  GND_A16  = GND
  PERN0  = P2E_CPU0_P5_TX_C_DP
  PERP0  = P2E_CPU0_P5_TX_C_DN
  GND_A19  = GND
  PERN1  = P2E_CPU0_P5_RX_DP
  PERP1  = P2E_CPU0_P5_RX_DN
  GND_A22  = GND
  PERN2  = SMB_PCIE0_3V3AUX_SCL
  PERP2  = SMB_PCIE0_3V3AUX_SDA
  GND_A25  = SMB_PMBUS_3V3AUX_SCL_R0
  PERN3  = SMB_PMBUS_3V3AUX_SDA_R0
  PERP3  = SMB_1_PLD_3V3AUX_SCL_R3
  GND_A28  = SMB_1_PLD_3V3AUX_SDA_R3
  GND_A29  = SMB_FAN_3V3AUX_SCL
  PERN4  = SMB_FAN_3V3AUX_SDA
  PERP4  = SMB_PCIE2_3V3AUX_SCL_R0
  GND_A32  = SMB_PCIE2_3V3AUX_SDA_R0
  PERN5  = GND
  PERP5  = JTAG_SCM_TCK
  GND_A35  = JTAG_SCM_TMS
  PERN6  = JTAG_SCM_TDI_R
  PERP6  = JTAG_SCM_TDO_R
  GND_A38  = SMB_PCIE3_3V3AUX_SCL_R
  PERN7  = SMB_PCIE3_3V3AUX_SDA_R
  PERP7  = SMB_HOST_CLK_3V3AUX_SCL_R0
  GND_A41  = SMB_HOST_CLK_3V3AUX_SDA_R0
  \prsntb1#\  = GND
  GND_A43  = FW_RECOVERY
  PERN8  = PWRGD_PS_PWROK_R
  PERP8  = TP_STBY_EN
  GND_A46  = RST_MB_STBY_R_N
  PERN9  = SCM_SYS_PWRBTN_R_N
  PERP9  = SCM_SYS_PWROK_R1
  GND_A49  = SCM_HDT_DBREQ_N
  PERN10  = PU_JTAG_DBP_BMC_PRDY_N
  PERP10  = FM_RST_PERST_SCM_N
  GND_A52  = FM_UARTSW_MSB_R
  PERN11  = SCM_ROT_CPU_RST_N
  PERP11  = TP_CHASI
  GND_A55  = FM_UARTSW_LSB_R
  PERN12  = IRQ0_A56
  PERP12  = FM_SCM_PRSNT1_N
  GND_A58  = GND
  PERN13  = USB3_CPU0_BMC_RX_DP
  PERP13  = USB3_CPU0_BMC_RX_DN
  GND_A61  = GND
  PERN14  = TP_PCIE_RXP<1>
  PERP14  = TP_PCIE_RXN<1>
  GND_A64  = GND
  PERN15  = P2E_MB_BMC_RX_BUF_DP<0>
  PERP15  = P2E_MB_BMC_RX_BUF_DN<0>
  GND_A67  = GND
  USB_DATN  = CLK_100M_BMC_RC_DP
  USB_DATP  = CLK_100M_BMC_RC_DN
  \pwrbrk0#\  = GND
  \+12v_edge_b1\  = CLK_ESPI_CPU0_CLK1
  \+12v_edge_b2\  = ESPI_CPU0_CS1_N
  \+12v_edge_b3\  = ESPI_CPU0_ALERT_N
  \+12v_edge_b4\  = RST_ESPI_CPU0_RSTOUT_N
  \+12v_edge_b5\  = ESPI_CPU0_D0
  \+12v_edge_b6\  = ESPI_CPU0_D1
  \bif0#\  = ESPI_CPU0_D2
  \bif1#\  = ESPI_CPU0_D3
  \bif2#\  = FM_LPC_ESPI_SEL
  \perst0#\  = GND
  \+3.3v_edge\  = SPI_CPU0_LVC3_SCM_CLK
  AUX_PWR_EN  = SPI_CPU0_LVC3_SCM_CS0_N
  GND_B13  = SPI_CPU0_LVC3_SCM_D0
  REFCLKN0  = SPI_CPU0_LVC3_SCM_D1
  REFCLKP0  = SPI_CPU0_LVC3_SCM_D2
  GND_B16  = SPI_CPU0_LVC3_SCM_D3
  PETN0  = GND
  PETP0  = CLK_50M_RMII_BMC_OCP
  GND_B19  = RMII_OCP_BMC_CRSDV
  PETN1  = RMII_BMC_OCP_TX_EN
  PETP1  = RMII_BMC_OCP_TXD_0
  GND_B22  = RMII_BMC_OCP_TXD_1
  PETN2  = RMII_BMC_OCP_RX_ER
  PETP2  = RMII_OCP_BMC_RXD_0
  GND_B25  = RMII_OCP_BMC_RXD_1
  PETN3  = GND
  PETP3  = TP_PECI_BMC
  GND_B28  = TP_PVCCIO_PECI_BMC
  GND_B29  = SGPIO_SCM_DO_R_<0>
  PETN4  = SGPIO_SCM_CLK_R_<0>
  PETP4  = SGPIO_SCM_DI_R_<0>
  GND_B32  = SGPIO_SCM_LD_R_<0>
  PETN5  = GND
  PETP5  = SGPIO_SCM_DO_R_<1>
  GND_B35  = SGPIO_SCM_CLK_R_<1>
  PETN6  = SGPIO_SCM_DI_R_<1>
  PETP6  = SGPIO_SCM_LD_R_<1>
  GND_B38  = GND
  PETN7  = SGPIO_SCM_RESET_R_N
  PETP7  = SGPIO_SCM_INTR_R1_N
  GND_B41  = SCM_VDD_RTC
  \prsntb0#\  = FM_AC_PWR_BTN_N
  GND_B43  = TP_SPI_2_PLD_CLK
  PETN8  = TP_SPI_2_PLD_CS_N
  PETP8  = TP_SPI_2_PLD_IO0
  GND_B46  = TP_SPI_2_PLD_IO1
  PETN9  = TP_SPI_2_PLD_IO2
  PETP9  = TP_SPI_2_PLD_IO3
  GND_B49  = GND
  PETN10  = USB2_HOST_BMC_B_DP
  PETP10  = USB2_HOST_BMC_B_DN
  GND_B52  = GND
  PETN11  = USB2_CPU0_P1_DP
  PETP11  = USB2_CPU0_P1_DN
  GND_B55  = GND
  PETN12  = USB2_HUB_EXT_DP
  PETP12  = USB2_HUB_EXT_DN
  GND_B58  = GND
  PETN13  = USB3_CPU0_BMC_TX_BUF_C_DP
  PETP13  = USB3_CPU0_BMC_TX_BUF_C_DN
  GND_B61  = GND
  PETN14  = TP_PCIE_TXP<1>
  PETP14  = TP_PCIE_TXN<1>
  GND_B64  = GND
  PETN15  = P2E_MB_BMC_TX_C_DP<0>
  PETP15  = P2E_MB_BMC_TX_C_DN<0>
  GND_B67  = GND
  RFU1_NC_B68  = TP_PCIE_TXP<3>
  RFU1_NC_B69  = TP_BEEP_LED
  \prsntb3#\  = GND
  G1  = GND
  G2  = GND
  G3  = GND
  G4  = GND
  G5  = GND
  \perst2#\  = P12V_SCM
  \perst3#\  = P12V_SCM
  \wake#\  = GND
  RBT_ARB_IN  = GND
  RBT_ARB_OUT  = I3C_SCM_0_SCL
  SLOT_ID1  = I3C_SCM_0_SDA
  RBT_TX_EN  = I3C_SCM_1_SCL
  RBT_TXD1  = I3C_SCM_1_SDA
  RBT_TXD0  = I3C_SCM_2_SCL
  GND_OA10  = I3C_SCM_2_SDA
  REFCLKN3  = I3C_SCM_3_SCL
  REFCLKP3  = I3C_SCM_3_SDA
  GND_OA13  = GND
  RBT_CLK_IN  = VIRTUAL_RESEAT
  NIC_PWR_GOOD  = P12V_SCM
  MAIN_PWR_EN  = P12V_SCM
  \ld#\  = PRSNT0_N
  DATA_IN  = GND
  DATA_OUT  = UART_BMC_BIC_TX
  CLK  = UART_BMC_BIC_BUF_RX
  SLOT_ID0  = GND
  RBT_RXD1  = UART_CPU0_SCM_LVC3_UART1_RX
  RBT_RXD0  = UART_CPU0_SCM_LVC3_UART1_R1_TX
  GND_OB10  = GND
  REFCLKN2  = RST_SRST_PLD_BMC_N
  REFCLKP2  = SPI_CPU0_LVC3_TPM_CS_N
  GND_OB13  = FPGA_IO3V3_RSVD_1
  RBT_CRS_DV  = FM_SOL_UART_CH_SEL_R

(kicad_pcb
	(version 20260206)
	(generator "pcbnew")
	(generator_version "10.0")
	(general
		(thickness 1.6)
		(legacy_teardrops no)
	)
	(paper "A4")
	(title_block
		(title "04192023_DAF0TMB3IC0_F0TG_MB_C_brd_V02_OCP.brd")
		(comment 1 "Grand Teton / footprint 3166 of 8354 (J41), pads 88-131 of 175")
	)
	(layers
		(0 "F.Cu" signal "TOP")
		(4 "In1.Cu" signal "GND")
		(6 "In2.Cu" signal "IN1")
		(8 "In3.Cu" signal "GND1")
		(10 "In4.Cu" signal "IN2")
		(12 "In5.Cu" signal "GND2")
		(14 "In6.Cu" signal "IN3")
		(16 "In7.Cu" signal "GND3")
		(18 "In8.Cu" signal "VCC")
		(20 "In9.Cu" signal "VCC1")
		(22 "In10.Cu" signal "GND4")
		(24 "In11.Cu" signal "IN4")
		(26 "In12.Cu" signal "GND5")
		(28 "In13.Cu" signal "IN5")
		(30 "In14.Cu" signal "GND6")
		(32 "In15.Cu" signal "IN6")
		(34 "In16.Cu" signal "GND7")
		(2 "B.Cu" signal "BOTTOM")
		(9 "F.Adhes" user "F.Adhesive")
		(11 "B.Adhes" user "B.Adhesive")
		(13 "F.Paste" user "Package Geometry/Pastemask Top")
		(15 "B.Paste" user "Package Geometry/Pastemask Bottom")
		(5 "F.SilkS" user "Ref Des/Silkscreen Top")
		(7 "B.SilkS" user "Ref Des/Silkscreen Bottom")
		(1 "F.Mask" user "Board Geometry/Soldermask Top")
		(3 "B.Mask" user "Board Geometry/Soldermask Bottom")
		(17 "Dwgs.User" user "User.Drawings")
		(19 "Cmts.User" user "User.Comments")
		(21 "Eco1.User" user "User.Eco1")
		(23 "Eco2.User" user "User.Eco2")
		(25 "Edge.Cuts" user "Board Geometry/Outline")
		(27 "Margin" user)
		(31 "F.CrtYd" user "Package Geometry/Place Bound Top")
		(29 "B.CrtYd" user "Package Geometry/Place Bound Bottom")
		(35 "F.Fab" user "Ref Des/Assembly Top")
		(33 "B.Fab" user "Ref Des/Assembly Bottom")
	)
	(footprint ""
		(layer "F.Cu")
		(at 160.402016 -10.849864 -90)
		(property "Reference" "J41"
			(at -8.65886 -21.78558 0)
			(unlocked yes)
			(layer "F.SilkS")
			(effects
				(font
					(size 0.7874 0.5842)
					(thickness 0.1524)
				)
				(justify left)
			)
		)
		(property "Value" ""
			(at 0 0 270)
			(layer "F.Fab")
			(effects
				(font
					(size 1.27 1.27)
				)
			)
		)
		(duplicate_pad_numbers_are_jumpers no)
		(pad "B16" smd rect
			(at -5.700014 -9.465056 180)
			(size 0.381 1.4478)
			(layers "F.Cu" "F.Mask" "F.Paste")
			(net "SPI_CPU0_LVC3_SCM_D3")
		)
		(pad "B17" smd rect
			(at -5.700014 -8.865108 180)
			(size 0.381 1.4478)
			(layers "F.Cu" "F.Mask" "F.Paste")
			(net "GND")
		)
		(pad "B18" smd rect
			(at -5.700014 -8.264906 180)
			(size 0.381 1.4478)
			(layers "F.Cu" "F.Mask" "F.Paste")
			(net "CLK_50M_RMII_BMC_OCP")
		)
		(pad "B19" smd rect
			(at -5.700014 -7.664958 180)
			(size 0.381 1.4478)
			(layers "F.Cu" "F.Mask" "F.Paste")
			(net "RMII_OCP_BMC_CRSDV")
		)
		(pad "B20" smd rect
			(at -5.700014 -7.06501 180)
			(size 0.381 1.4478)
			(layers "F.Cu" "F.Mask" "F.Paste")
			(net "RMII_BMC_OCP_TX_EN")
		)
		(pad "B21" smd rect
			(at -5.700014 -6.465062 180)
			(size 0.381 1.4478)
			(layers "F.Cu" "F.Mask" "F.Paste")
			(net "RMII_BMC_OCP_TXD_0")
		)
		(pad "B22" smd rect
			(at -5.700014 -5.865114 180)
			(size 0.381 1.4478)
			(layers "F.Cu" "F.Mask" "F.Paste")
			(net "RMII_BMC_OCP_TXD_1")
		)
		(pad "B23" smd rect
			(at -5.700014 -5.264912 180)
			(size 0.381 1.4478)
			(layers "F.Cu" "F.Mask" "F.Paste")
			(net "RMII_BMC_OCP_RX_ER")
		)
		(pad "B24" smd rect
			(at -5.700014 -4.664964 180)
			(size 0.381 1.4478)
			(layers "F.Cu" "F.Mask" "F.Paste")
			(net "RMII_OCP_BMC_RXD_0")
		)
		(pad "B25" smd rect
			(at -5.700014 -4.065016 180)
			(size 0.381 1.4478)
			(layers "F.Cu" "F.Mask" "F.Paste")
			(net "RMII_OCP_BMC_RXD_1")
		)
		(pad "B26" smd rect
			(at -5.700014 -3.465068 180)
			(size 0.381 1.4478)
			(layers "F.Cu" "F.Mask" "F.Paste")
			(net "GND")
		)
		(pad "B27" smd rect
			(at -5.700014 -2.86512 180)
			(size 0.381 1.4478)
			(layers "F.Cu" "F.Mask" "F.Paste")
			(net "TP_PECI_BMC")
		)
		(pad "B28" smd rect
			(at -5.700014 -2.264918 180)
			(size 0.381 1.4478)
			(layers "F.Cu" "F.Mask" "F.Paste")
			(net "TP_PVCCIO_PECI_BMC")
		)
		(pad "B29" smd rect
			(at -5.700014 1.74498 180)
			(size 0.381 1.4478)
			(layers "F.Cu" "F.Mask" "F.Paste")
			(net "SGPIO_SCM_DO_R_<0>")
		)
		(pad "B30" smd rect
			(at -5.700014 2.344928 180)
			(size 0.381 1.4478)
			(layers "F.Cu" "F.Mask" "F.Paste")
			(net "SGPIO_SCM_CLK_R_<0>")
		)
		(pad "B31" smd rect
			(at -5.700014 2.944876 180)
			(size 0.381 1.4478)
			(layers "F.Cu" "F.Mask" "F.Paste")
			(net "SGPIO_SCM_DI_R_<0>")
		)
		(pad "B32" smd rect
			(at -5.700014 3.545078 180)
			(size 0.381 1.4478)
			(layers "F.Cu" "F.Mask" "F.Paste")
			(net "SGPIO_SCM_LD_R_<0>")
		)
		(pad "B33" smd rect
			(at -5.700014 4.145026 180)
			(size 0.381 1.4478)
			(layers "F.Cu" "F.Mask" "F.Paste")
			(net "GND")
		)
		(pad "B34" smd rect
			(at -5.700014 4.744974 180)
			(size 0.381 1.4478)
			(layers "F.Cu" "F.Mask" "F.Paste")
			(net "SGPIO_SCM_DO_R_<1>")
		)
		(pad "B35" smd rect
			(at -5.700014 5.344922 180)
			(size 0.381 1.4478)
			(layers "F.Cu" "F.Mask" "F.Paste")
			(net "SGPIO_SCM_CLK_R_<1>")
		)
		(pad "B36" smd rect
			(at -5.700014 5.945124 180)
			(size 0.381 1.4478)
			(layers "F.Cu" "F.Mask" "F.Paste")
			(net "SGPIO_SCM_DI_R_<1>")
		)
		(pad "B37" smd rect
			(at -5.700014 6.545072 180)
			(size 0.381 1.4478)
			(layers "F.Cu" "F.Mask" "F.Paste")
			(net "SGPIO_SCM_LD_R_<1>")
		)
		(pad "B38" smd rect
			(at -5.700014 7.14502 180)
			(size 0.381 1.4478)
			(layers "F.Cu" "F.Mask" "F.Paste")
			(net "GND")
		)
		(pad "B39" smd rect
			(at -5.700014 7.744968 180)
			(size 0.381 1.4478)
			(layers "F.Cu" "F.Mask" "F.Paste")
			(net "SGPIO_SCM_RESET_R_N")
		)
		(pad "B40" smd rect
			(at -5.700014 8.344916 180)
			(size 0.381 1.4478)
			(layers "F.Cu" "F.Mask" "F.Paste")
			(net "SGPIO_SCM_INTR_R1_N")
		)
		(pad "B41" smd rect
			(at -5.700014 8.945118 180)
			(size 0.381 1.4478)
			(layers "F.Cu" "F.Mask" "F.Paste")
			(net "SCM_VDD_RTC")
		)
		(pad "B42" smd rect
			(at -5.700014 9.545066 180)
			(size 0.381 1.4478)
			(layers "F.Cu" "F.Mask" "F.Paste")
			(net "FM_AC_PWR_BTN_N")
		)
		(pad "B43" smd rect
			(at -5.700014 14.454886 180)
			(size 0.381 1.4478)
			(layers "F.Cu" "F.Mask" "F.Paste")
			(net "TP_SPI_2_PLD_CLK")
		)
		(pad "B44" smd rect
			(at -5.700014 15.055088 180)
			(size 0.381 1.4478)
			(layers "F.Cu" "F.Mask" "F.Paste")
			(net "TP_SPI_2_PLD_CS_N")
		)
		(pad "B45" smd rect
			(at -5.700014 15.655036 180)
			(size 0.381 1.4478)
			(layers "F.Cu" "F.Mask" "F.Paste")
			(net "TP_SPI_2_PLD_IO0")
		)
		(pad "B46" smd rect
			(at -5.700014 16.254984 180)
			(size 0.381 1.4478)
			(layers "F.Cu" "F.Mask" "F.Paste")
			(net "TP_SPI_2_PLD_IO1")
		)
		(pad "B47" smd rect
			(at -5.700014 16.854932 180)
			(size 0.381 1.4478)
			(layers "F.Cu" "F.Mask" "F.Paste")
			(net "TP_SPI_2_PLD_IO2")
		)
		(pad "B48" smd rect
			(at -5.700014 17.45488 180)
			(size 0.381 1.4478)
			(layers "F.Cu" "F.Mask" "F.Paste")
			(net "TP_SPI_2_PLD_IO3")
		)
		(pad "B49" smd rect
			(at -5.700014 18.055082 180)
			(size 0.381 1.4478)
			(layers "F.Cu" "F.Mask" "F.Paste")
			(net "GND")
		)
		(pad "B50" smd rect
			(at -5.700014 18.65503 180)
			(size 0.381 1.4478)
			(layers "F.Cu" "F.Mask" "F.Paste")
			(net "USB2_HOST_BMC_B_DP")
		)
		(pad "B51" smd rect
			(at -5.700014 19.254978 180)
			(size 0.381 1.4478)
			(layers "F.Cu" "F.Mask" "F.Paste")
			(net "USB2_HOST_BMC_B_DN")
		)
		(pad "B52" smd rect
			(at -5.700014 19.854926 180)
			(size 0.381 1.4478)
			(layers "F.Cu" "F.Mask" "F.Paste")
			(net "GND")
		)
		(pad "B53" smd rect
			(at -5.700014 20.455128 180)
			(size 0.381 1.4478)
			(layers "F.Cu" "F.Mask" "F.Paste")
			(net "USB2_CPU0_P1_DP")
		)
		(pad "B54" smd rect
			(at -5.700014 21.055076 180)
			(size 0.381 1.4478)
			(layers "F.Cu" "F.Mask" "F.Paste")
			(net "USB2_CPU0_P1_DN")
		)
		(pad "B55" smd rect
			(at -5.700014 21.655024 180)
			(size 0.381 1.4478)
			(layers "F.Cu" "F.Mask" "F.Paste")
			(net "GND")
		)
		(pad "B56" smd rect
			(at -5.700014 22.254972 180)
			(size 0.381 1.4478)
			(layers "F.Cu" "F.Mask" "F.Paste")
			(net "USB2_HUB_EXT_DP")
		)
		(pad "B57" smd rect
			(at -5.700014 22.85492 180)
			(size 0.381 1.4478)
			(layers "F.Cu" "F.Mask" "F.Paste")
			(net "USB2_HUB_EXT_DN")
		)
		(pad "B58" smd rect
			(at -5.700014 23.455122 180)
			(size 0.381 1.4478)
			(layers "F.Cu" "F.Mask" "F.Paste")
			(net "GND")
		)
		(pad "B59" smd rect
			(at -5.700014 24.05507 180)
			(size 0.381 1.4478)
			(layers "F.Cu" "F.Mask" "F.Paste")
			(net "USB3_CPU0_BMC_TX_BUF_C_DP")
		)
	)
)
